# T6G (Grand Teton) — schematic netlist excerpt (pin names and nets, part order shuffled) for the footprints in the layout excerpt that follows; sources: Cadence DE-HDL packaged netlist, KiCad conversion of 04192023_DAF0TMB3IC0_F0TG_MB_C_brd_V02_OCP.brd

R3216  Q_RES  100 1% CHIP  pkg 0402LF  page 138 : A = OCP_V3_2_ISO_BIF1_EN ; B = GND
R505  Q_RES  15 1% CHIP  pkg 0402LF  page 42 : A = M_F_CPU1_ALERT_N ; B = M_F_CPU1_ALERT_R_N

(kicad_pcb
	(version 20260206)
	(generator "pcbnew")
	(generator_version "10.0")
	(general
		(thickness 1.6)
		(legacy_teardrops no)
	)
	(paper "A4")
	(title_block
		(title "04192023_DAF0TMB3IC0_F0TG_MB_C_brd_V02_OCP.brd")
		(comment 1 "Grand Teton / footprints 6413-6414 of 8354")
	)
	(layers
		(0 "F.Cu" signal "TOP")
		(4 "In1.Cu" signal "GND")
		(6 "In2.Cu" signal "IN1")
		(8 "In3.Cu" signal "GND1")
		(10 "In4.Cu" signal "IN2")
		(12 "In5.Cu" signal "GND2")
		(14 "In6.Cu" signal "IN3")
		(16 "In7.Cu" signal "GND3")
		(18 "In8.Cu" signal "VCC")
		(20 "In9.Cu" signal "VCC1")
		(22 "In10.Cu" signal "GND4")
		(24 "In11.Cu" signal "IN4")
		(26 "In12.Cu" signal "GND5")
		(28 "In13.Cu" signal "IN5")
		(30 "In14.Cu" signal "GND6")
		(32 "In15.Cu" signal "IN6")
		(34 "In16.Cu" signal "GND7")
		(2 "B.Cu" signal "BOTTOM")
		(9 "F.Adhes" user "F.Adhesive")
		(11 "B.Adhes" user "B.Adhesive")
		(13 "F.Paste" user "Package Geometry/Pastemask Top")
		(15 "B.Paste" user "Package Geometry/Pastemask Bottom")
		(5 "F.SilkS" user "Ref Des/Silkscreen Top")
		(7 "B.SilkS" user "Ref Des/Silkscreen Bottom")
		(1 "F.Mask" user "Board Geometry/Soldermask Top")
		(3 "B.Mask" user "Board Geometry/Soldermask Bottom")
		(17 "Dwgs.User" user "User.Drawings")
		(19 "Cmts.User" user "User.Comments")
		(21 "Eco1.User" user "User.Eco1")
		(23 "Eco2.User" user "User.Eco2")
		(25 "Edge.Cuts" user "Board Geometry/Outline")
		(27 "Margin" user)
		(31 "F.CrtYd" user "Package Geometry/Place Bound Top")
		(29 "B.CrtYd" user "Package Geometry/Place Bound Bottom")
		(35 "F.Fab" user "Ref Des/Assembly Top")
		(33 "B.Fab" user "Ref Des/Assembly Bottom")
	)
	(footprint ""
		(layer "B.Cu")
		(at 61.413898 -15.58036 90)
		(property "Reference" "R3216"
			(at 0 0 90)
			(layer "B.SilkS")
			(hide yes)
			(effects
				(font
					(size 1.27 1.27)
				)
				(justify mirror)
			)
		)
		(property "Value" ""
			(at 0 0 90)
			(layer "B.Fab")
			(effects
				(font
					(size 1.27 1.27)
				)
				(justify mirror)
			)
		)
		(duplicate_pad_numbers_are_jumpers no)
		(fp_line
			(start 0.7874 -0.4064)
			(end -0.7874 -0.4064)
			(stroke
				(width 0.1524)
				(type default)
			)
			(layer "B.SilkS")
		)
		(fp_line
			(start -0.7874 -0.4064)
			(end -0.7874 0.4064)
			(stroke
				(width 0.1524)
				(type default)
			)
			(layer "B.SilkS")
		)
		(fp_line
			(start 0.7874 0.4064)
			(end 0.7874 -0.4064)
			(stroke
				(width 0.1524)
				(type default)
			)
			(layer "B.SilkS")
		)
		(fp_line
			(start -0.7874 0.4064)
			(end 0.7874 0.4064)
			(stroke
				(width 0.1524)
				(type default)
			)
			(layer "B.SilkS")
		)
		(fp_line
			(start 0.67945 -0.305054)
			(end 0.12065 -0.305054)
			(stroke
				(width 0.1)
				(type default)
			)
			(layer "B.Fab")
		)
		(fp_line
			(start 0.12065 -0.305054)
			(end 0.12065 -0.2794)
			(stroke
				(width 0.1)
				(type default)
			)
			(layer "B.Fab")
		)
		(fp_line
			(start -0.12065 -0.3048)
			(end -0.67945 -0.3048)
			(stroke
				(width 0.1)
				(type default)
			)
			(layer "B.Fab")
		)
		(fp_line
			(start -0.67945 -0.3048)
			(end -0.67945 0.3048)
			(stroke
				(width 0.1)
				(type default)
			)
			(layer "B.Fab")
		)
		(fp_line
			(start 0.12065 -0.2794)
			(end -0.12065 -0.2794)
			(stroke
				(width 0.1)
				(type default)
			)
			(layer "B.Fab")
		)
		(fp_line
			(start -0.12065 -0.2794)
			(end -0.12065 -0.3048)
			(stroke
				(width 0.1)
				(type default)
			)
			(layer "B.Fab")
		)
		(fp_line
			(start 0.12065 0.2794)
			(end 0.12065 0.3048)
			(stroke
				(width 0.1)
				(type default)
			)
			(layer "B.Fab")
		)
		(fp_line
			(start -0.120396 0.2794)
			(end 0.12065 0.2794)
			(stroke
				(width 0.1)
				(type default)
			)
			(layer "B.Fab")
		)
		(fp_line
			(start 0.67945 0.3048)
			(end 0.67945 -0.305054)
			(stroke
				(width 0.1)
				(type default)
			)
			(layer "B.Fab")
		)
		(fp_line
			(start 0.12065 0.3048)
			(end 0.67945 0.3048)
			(stroke
				(width 0.1)
				(type default)
			)
			(layer "B.Fab")
		)
		(fp_line
			(start -0.120396 0.3048)
			(end -0.120396 0.2794)
			(stroke
				(width 0.1)
				(type default)
			)
			(layer "B.Fab")
		)
		(fp_line
			(start -0.67945 0.3048)
			(end -0.120396 0.3048)
			(stroke
				(width 0.1)
				(type default)
			)
			(layer "B.Fab")
		)
		(pad "1" smd circle
			(at 0.40005 0 270)
			(size 0 0)
			(layers "B.Cu" "B.Mask" "B.Paste")
			(net "OCP_V3_2_ISO_BIF1_EN")
		)
		(pad "2" smd circle
			(at -0.40005 0 270)
			(size 0 0)
			(layers "B.Cu" "B.Mask" "B.Paste")
			(net "GND")
		)
	)
	(footprint ""
		(layer "B.Cu")
		(at 22.70506 -244.085364 180)
		(property "Reference" "R505"
			(at 0 0 0)
			(layer "B.SilkS")
			(hide yes)
			(effects
				(font
					(size 1.27 1.27)
				)
				(justify mirror)
			)
		)
		(property "Value" ""
			(at 0 0 0)
			(layer "B.Fab")
			(effects
				(font
					(size 1.27 1.27)
				)
				(justify mirror)
			)
		)
		(duplicate_pad_numbers_are_jumpers no)
		(fp_line
			(start 0.7874 0.4064)
			(end 0.7874 -0.4064)
			(stroke
				(width 0.1524)
				(type default)
			)
			(layer "B.SilkS")
		)
		(fp_line
			(start 0.7874 -0.4064)
			(end -0.7874 -0.4064)
			(stroke
				(width 0.1524)
				(type default)
			)
			(layer "B.SilkS")
		)
		(fp_line
			(start -0.7874 0.4064)
			(end 0.7874 0.4064)
			(stroke
				(width 0.1524)
				(type default)
			)
			(layer "B.SilkS")
		)
		(fp_line
			(start -0.7874 -0.4064)
			(end -0.7874 0.4064)
			(stroke
				(width 0.1524)
				(type default)
			)
			(layer "B.SilkS")
		)
		(fp_line
			(start 0.67945 0.3048)
			(end 0.67945 -0.305054)
			(stroke
				(width 0.1)
				(type default)
			)
			(layer "B.Fab")
		)
		(fp_line
			(start 0.67945 -0.305054)
			(end 0.12065 -0.305054)
			(stroke
				(width 0.1)
				(type default)
			)
			(layer "B.Fab")
		)
		(fp_line
			(start 0.12065 0.3048)
			(end 0.67945 0.3048)
			(stroke
				(width 0.1)
				(type default)
			)
			(layer "B.Fab")
		)
		(fp_line
			(start 0.12065 0.2794)
			(end 0.12065 0.3048)
			(stroke
				(width 0.1)
				(type default)
			)
			(layer "B.Fab")
		)
		(fp_line
			(start 0.12065 -0.2794)
			(end -0.12065 -0.2794)
			(stroke
				(width 0.1)
				(type default)
			)
			(layer "B.Fab")
		)
		(fp_line
			(start 0.12065 -0.305054)
			(end 0.12065 -0.2794)
			(stroke
				(width 0.1)
				(type default)
			)
			(layer "B.Fab")
		)
		(fp_line
			(start -0.120396 0.3048)
			(end -0.120396 0.2794)
			(stroke
				(width 0.1)
				(type default)
			)
			(layer "B.Fab")
		)
		(fp_line
			(start -0.120396 0.2794)
			(end 0.12065 0.2794)
			(stroke
				(width 0.1)
				(type default)
			)
			(layer "B.Fab")
		)
		(fp_line
			(start -0.12065 -0.2794)
			(end -0.12065 -0.3048)
			(stroke
				(width 0.1)
				(type default)
			)
			(layer "B.Fab")
		)
		(fp_line
			(start -0.12065 -0.3048)
			(end -0.67945 -0.3048)
			(stroke
				(width 0.1)
				(type default)
			)
			(layer "B.Fab")
		)
		(fp_line
			(start -0.67945 0.3048)
			(end -0.120396 0.3048)
			(stroke
				(width 0.1)
				(type default)
			)
			(layer "B.Fab")
		)
		(fp_line
			(start -0.67945 -0.3048)
			(end -0.67945 0.3048)
			(stroke
				(width 0.1)
				(type default)
			)
			(layer "B.Fab")
		)
		(pad "1" smd circle
			(at 0.40005 0)
			(size 0 0)
			(layers "B.Cu" "B.Mask" "B.Paste")
			(net "M_F_CPU1_ALERT_N")
		)
		(pad "2" smd circle
			(at -0.40005 0)
			(size 0 0)
			(layers "B.Cu" "B.Mask" "B.Paste")
			(net "M_F_CPU1_ALERT_R_N")
		)
	)
)
